FILE_TYPE = MACRO_DRAWING;
SET COLOR_WIRE YELLOW;
SET COLOR_PROP ORANGE;
SET COLOR_DOT WHITE;
SET COLOR_ARC YELLOW;
SET COLOR_BODY GREEN;
SET COLOR_NOTE PURPLE;
SET PROP_DISPLAY VALUE;
SET PAGE_NUMBER P158;
FORCEADD QUANTA_TITLE_BLOCK_C..1
(200 50);
FORCEPROP 1 LAST CUSTOM_TXT_CDS <NAME_2>
J 0
(-2975 100);
FORCEPROP 1 LAST CUSTOM_TXT_CDS <NAME_1>
J 0
(-2975 225);
FORCEPROP 1 LAST CUSTOM_TXT_CDS <Q_NUMBER>
J 0
(-1203 153);
DISPLAY 1.212766 (-1203 153);
FORCEPROP 1 LAST CUSTOM_TXT_CDS <Q_PROJ>
J 0
(-2182 152);
DISPLAY 1.212766 (-2182 152);
FORCEPROP 1 LAST CUSTOM_TXT_CDS <Q_REV>
J 0
(16 153);
DISPLAY 1.212766 (16 153);
FORCEPROP 1 LAST CUSTOM_TXT_CDS <CON_LAST_MODIFIED>
J 0
(-1685 65);
DISPLAY 0.978723 (-1685 65);
FORCEPROP 1 LAST CUSTOM_TXT_CDS <CON_PAGE_NUM> OF <CON_TOTAL_PAGES>
J 0
(-246 68);
DISPLAY 0.978723 (-246 68);
FORCEPROP 1 LAST Q_TITLE PMDU CONN
J 0
(-9075 125);
DISPLAY 2.446809 (-9075 125);
PAINT GREEN (-9075 125);
FORCEPROP 1 LAST Q_DEPT BU9
J 1
(-3563 99);
DISPLAY 1.957447 (-3563 99);
PAINT GREEN (-3563 99);
FORCEPROP 1 LAST COMMENT_BODY TRUE
J 0
(212 37);
DISPLAY 0.978723 (212 37);
PAINT GREEN (212 37);
DISPLAY INVISIBLE (212 37);
FORCEPROP 2 LAST CDS_LIB pure_quanta
J 0
(200 50);
DISPLAY INVISIBLE (200 50);
FORCEPROP 1 LAST CDS_LMAN_SYM_OUTLINE -9475,6775,100,-125
J 0
(200 50);
DISPLAY 0.468085 (200 50);
PAINT GREEN (200 50);
DISPLAY INVISIBLE (200 50);
FORCEPROP 2 LAST PAGE_BORDER TRUE
J 0
(-7690 5300);
DISPLAY 0.638298 (-7690 5300);
PAINT PINK (-7690 5300);
DISPLAY INVISIBLE (-7690 5300);
FORCEPROP 2 LAST CDS_XR_PAGE_TITLE CR-158 : @T6G_MB_LIB.T6G(SCH_1):PAGE158
J 0
(-7690 5300);
DISPLAY 0.638298 (-7690 5300);
PAINT PINK (-7690 5300);
DISPLAY INVISIBLE (-7690 5300);
FORCEPROP 2 LAST CUSTOM_TXT_CDS <XR_PAGE_TITLE>
J 0
(-7690 5300);
DISPLAY 0.638298 (-7690 5300);
PAINT PINK (-7690 5300);
DISPLAY INVISIBLE (-7690 5300);
FORCEPROP 0 LAST CDS_CON_LAST_MODIFIED Wed Mar 09 20:29:45 2022
J 0
(-1685 65);
DISPLAY INVISIBLE (-1685 65);
QUIT
